FILE_TYPE = CONNECTIVITY;
{Allegro Design Entry HDL 16.6-p007 (v16-6-112F) 10/10/2012}
"PAGE_NUMBER" = 151;
0"NC";
1"GND\g";
2"P3V3_STBY\g";
3"SPI_BMC_BT_DO";
4"GPIOS7";
5"H_CPU0_MEMDEF_MEMHOT_LVT3_BMC_N";
6"H_CPU0_MEMABC_MEMHOT_LVT3_BMC_N";
7"FM_CPU0_THERMTRIP_LATCH_LVT3_N";
8"HSC_SMBUS_SWITCH_EN";
9"RMII_BMC_OCP_TXEN";
10"JTAG_BMC_TRST_N";
11"FM_CPU1_PROC_ID0";
12"TP_RGMII1TXD3_GPIOT5";
13"FP_PWR_ID_LED_N";
14"RMII_BMC_OCP_TXD0_R";
15"RMII_BMC_OCP_TXD1_R";
16"TP_RGMII2TXD3_GPIOT5";
17"TP_RGMII2TXD2_GPIOT4";
18"UART_BMC_TXD5";
19"RMII_BMC_PCH_SPRNGVLLE_TXD1_R";
20"RMII_BMC_PCH_SPRNGVLLE_TXEN";
21"TP_RGMII1TXD2_GPIOT4";
22"SPI_BMC_BT_DI";
23"SPI_BMC_BT_CS_N";
24"SPI_BMC_BT_CLK";
25"RMII_BMC_PCH_SPRNGVLLE_TXD0_R";
%"GND"
"1","(-7325,125)","0","mstr_symbols","I1";
;
HDL_POWER"GND"
BODY_TYPE"PLUMBING"
CDS_LIB"mstr_symbols"
SIZE"1B"
VOLTAGE"0.0V";
"A\NAC"1;
%"RES"
"1","(-6900,4425)","0","mstr_discrete","I10";
;
CDS_SEC"1"
$SEC"1"
CDS_LOCATION"R25W96"
ROOM"BMC"
BOM_COST"SM_CONTROLLER"
CDS_LIB"mstr_discrete"
PACK_TYPE"0402"
WATTAGE"1/16W"
PART_NUMBER"G21796-072"
LOCATION"R25W96"
VALUE"4.75K"
TOLERANCE"1%"
MATERIAL"CHIP";
"B"
$PN"2"3;
"A"
$PN"1"2;
%"RES"
"1","(-6900,4275)","0","mstr_discrete","I11";
;
CDS_LOCATION"R25W97"
BOM_COST"SM_CONTROLLER"
CDS_SEC"1"
$SEC"1"
ROOM"BMC"
CDS_LIB"mstr_discrete"
WATTAGE"1/16W"
MATERIAL"EMPTY"
PART_NUMBER"G21796-072"
TOLERANCE"1%"
VALUE"4.75K"
PACK_TYPE"0402"
LOCATION"R25W97";
"B"
$PN"2"22;
"A"
$PN"1"2;
%"RES"
"1","(-6900,4000)","0","mstr_discrete","I12";
;
CDS_SEC"1"
$SEC"1"
CDS_LOCATION"R25W98"
ROOM"BMC"
BOM_COST"SM_CONTROLLER"
CDS_LIB"mstr_discrete"
PACK_TYPE"0402"
WATTAGE"1/16W"
VALUE"4.75K"
TOLERANCE"1%"
MATERIAL"CHIP"
PART_NUMBER"G21796-072"
LOCATION"R25W98";
"B"
$PN"2"5;
"A"
$PN"1"2;
%"RES"
"1","(-6900,3625)","0","mstr_discrete","I13";
;
CDS_SEC"1"
$SEC"1"
CDS_LOCATION"R25W100"
CDS_LIB"mstr_discrete"
BOM_COST"SM_CONTROLLER"
ROOM"BMC"
VALUE"4.75K"
PACK_TYPE"0402"
LOCATION"R25W100"
WATTAGE"1/16W"
TOLERANCE"1%"
MATERIAL"CHIP"
PART_NUMBER"G21796-072";
"B"
$PN"2"4;
"A"
$PN"1"2;
%"RES"
"1","(-6925,3825)","0","mstr_discrete","I14";
;
CDS_LOCATION"R25W99"
BOM_COST"SM_CONTROLLER"
CDS_SEC"1"
$SEC"1"
ROOM"BMC"
CDS_LIB"mstr_discrete"
PART_NUMBER"G21796-072"
VALUE"4.75K"
PACK_TYPE"0402"
LOCATION"R25W99"
TOLERANCE"1%"
WATTAGE"1/16W"
MATERIAL"EMPTY";
"B"
$PN"2"13;
"A"
$PN"1"2;
%"P3V3_STBY"
"1","(-7325,4850)","0","mstr_symbols","I15";
;
HDL_POWER"P3V3_STBY"
BODY_TYPE"PLUMBING"
SIZE"1B"
VOLTAGE"3.3V"
CDS_LIB"mstr_symbols";
"G\NAC"2;
%"RES"
"1","(-6900,4550)","0","mstr_discrete","I2";
;
CDS_SEC"1"
$SEC"1"
CDS_LOCATION"R25W95"
CDS_LIB"mstr_discrete"
BOM_COST"SM_CONTROLLER"
ROOM"BMC"
PACK_TYPE"0402"
WATTAGE"1/16W"
TOLERANCE"1%"
MATERIAL"CHIP"
VALUE"4.75K"
LOCATION"R25W95"
PART_NUMBER"G21796-072";
"B"
$PN"2"24;
"A"
$PN"1"2;
%"RES"
"1","(-6900,3475)","0","mstr_discrete","I27";
;
CDS_LOCATION"R25W101"
BOM_COST"SM_CONTROLLER"
CDS_SEC"1"
$SEC"1"
ROOM"BMC"
CDS_LIB"mstr_discrete"
MATERIAL"EMPTY"
VALUE"4.75K"
TOLERANCE"1%"
PACK_TYPE"0402"
WATTAGE"1/16W"
LOCATION"R25W101"
PART_NUMBER"G21796-072";
"B"
$PN"2"8;
"A"
$PN"1"2;
%"RES"
"1","(-6900,3325)","0","mstr_discrete","I28";
;
CDS_SEC"1"
$SEC"1"
CDS_LOCATION"R25W102"
CDS_LIB"mstr_discrete"
BOM_COST"SM_CONTROLLER"
ROOM"BMC"
VALUE"4.75K"
WATTAGE"1/16W"
TOLERANCE"1%"
PACK_TYPE"0402"
MATERIAL"CHIP"
PART_NUMBER"G21796-072"
LOCATION"R25W102";
"B"
$PN"2"7;
"A"
$PN"1"2;
%"RES"
"1","(-6900,3175)","0","mstr_discrete","I29";
;
CDS_LOCATION"R25W103"
BOM_COST"SM_CONTROLLER"
CDS_SEC"1"
$SEC"1"
ROOM"BMC"
CDS_LIB"mstr_discrete"
WATTAGE"1/16W"
PART_NUMBER"G21796-072"
PACK_TYPE"0402"
MATERIAL"EMPTY"
TOLERANCE"1%"
VALUE"4.75K"
LOCATION"R25W103";
"B"
$PN"2"6;
"A"
$PN"1"2;
%"RES"
"1","(-6900,2950)","0","mstr_discrete","I30";
;
CDS_LOCATION"R25W104"
CDS_LIB"mstr_discrete"
ROOM"BMC"
$SEC"1"
CDS_SEC"1"
BOM_COST"SM_CONTROLLER"
WATTAGE"1/16W"
TOLERANCE"1%"
MATERIAL"EMPTY"
PART_NUMBER"G21796-072"
PACK_TYPE"0402"
LOCATION"R25W104"
VALUE"4.75K";
"B"
$PN"2"11;
"A"
$PN"1"2;
%"RES"
"1","(-6900,2725)","0","mstr_discrete","I31";
;
CDS_LOCATION"R25W105"
CDS_LIB"mstr_discrete"
ROOM"BMC"
$SEC"1"
CDS_SEC"1"
BOM_COST"SM_CONTROLLER"
PART_NUMBER"G21796-072"
VALUE"4.75K"
LOCATION"R25W105"
PACK_TYPE"0402"
WATTAGE"1/16W"
TOLERANCE"1%"
MATERIAL"EMPTY";
"B"
$PN"2"10;
"A"
$PN"1"2;
%"RES"
"1","(-6900,2500)","0","mstr_discrete","I32";
;
CDS_LOCATION"R25W106"
CDS_LIB"mstr_discrete"
ROOM"BMC"
$SEC"1"
CDS_SEC"1"
BOM_COST"SM_CONTROLLER"
PART_NUMBER"G21796-072"
LOCATION"R25W106"
MATERIAL"EMPTY"
PACK_TYPE"0402"
WATTAGE"1/16W"
VALUE"4.75K"
TOLERANCE"1%";
"B"
$PN"2"9;
"A"
$PN"1"2;
%"RES"
"1","(-6900,2275)","0","mstr_discrete","I33";
;
CDS_LOCATION"R25W107"
CDS_LIB"mstr_discrete"
ROOM"BMC"
$SEC"1"
CDS_SEC"1"
BOM_COST"SM_CONTROLLER"
LOCATION"R25W107"
PART_NUMBER"G21796-072"
VALUE"4.75K"
TOLERANCE"1%"
MATERIAL"EMPTY"
PACK_TYPE"0402"
WATTAGE"1/16W";
"B"
$PN"2"14;
"A"
$PN"1"2;
%"RES"
"1","(-6875,2075)","0","mstr_discrete","I34";
;
CDS_SEC"1"
$SEC"1"
CDS_LOCATION"R25W108"
ROOM"BMC"
BOM_COST"SM_CONTROLLER"
CDS_LIB"mstr_discrete"
TOLERANCE"1%"
MATERIAL"CHIP"
PACK_TYPE"0402"
VALUE"4.75K"
LOCATION"R25W108"
WATTAGE"1/16W"
PART_NUMBER"G21796-072";
"B"
$PN"2"15;
"A"
$PN"1"2;
%"RES"
"1","(-6875,1850)","0","mstr_discrete","I35";
;
CDS_LOCATION"R25W109"
CDS_LIB"mstr_discrete"
ROOM"BMC"
$SEC"1"
CDS_SEC"1"
BOM_COST"SM_CONTROLLER"
WATTAGE"1/16W"
PACK_TYPE"0402"
PART_NUMBER"G21796-072"
MATERIAL"EMPTY"
TOLERANCE"1%"
LOCATION"R25W109"
VALUE"4.75K";
"B"
$PN"2"16;
"A"
$PN"1"2;
%"RES"
"1","(-6850,1675)","0","mstr_discrete","I36";
;
CDS_SEC"1"
$SEC"1"
CDS_LOCATION"R25W110"
ROOM"BMC"
BOM_COST"SM_CONTROLLER"
CDS_LIB"mstr_discrete"
PART_NUMBER"G21796-072"
VALUE"4.75K"
MATERIAL"CHIP"
PACK_TYPE"0402"
WATTAGE"1/16W"
TOLERANCE"1%"
LOCATION"R25W110";
"B"
$PN"2"17;
"A"
$PN"1"2;
%"RES"
"1","(-6900,1400)","0","mstr_discrete","I43";
;
CDS_LOCATION"R25W111"
CDS_LIB"mstr_discrete"
ROOM"BMC"
$SEC"1"
CDS_SEC"1"
BOM_COST"SM_CONTROLLER"
TOLERANCE"1%"
WATTAGE"1/16W"
MATERIAL"EMPTY"
PACK_TYPE"0402"
LOCATION"R25W111"
VALUE"4.75K"
PART_NUMBER"G21796-072";
"B"
$PN"2"20;
"A"
$PN"1"2;
%"RES"
"1","(-6900,1175)","0","mstr_discrete","I44";
;
CDS_LOCATION"R25W112"
CDS_LIB"mstr_discrete"
ROOM"BMC"
$SEC"1"
CDS_SEC"1"
BOM_COST"SM_CONTROLLER"
PART_NUMBER"G21796-072"
WATTAGE"1/16W"
PACK_TYPE"0402"
VALUE"4.75K"
TOLERANCE"1%"
MATERIAL"EMPTY"
LOCATION"R25W112";
"B"
$PN"2"25;
"A"
$PN"1"2;
%"RES"
"1","(-6900,950)","0","mstr_discrete","I45";
;
CDS_LOCATION"R25W113"
CDS_LIB"mstr_discrete"
ROOM"BMC"
$SEC"1"
CDS_SEC"1"
BOM_COST"SM_CONTROLLER"
VALUE"4.75K"
MATERIAL"EMPTY"
WATTAGE"1/16W"
PACK_TYPE"0402"
TOLERANCE"1%"
PART_NUMBER"G21796-072"
LOCATION"R25W113";
"B"
$PN"2"19;
"A"
$PN"1"2;
%"RES"
"1","(-6900,725)","0","mstr_discrete","I46";
;
CDS_LOCATION"R25W114"
CDS_LIB"mstr_discrete"
ROOM"BMC"
$SEC"1"
CDS_SEC"1"
BOM_COST"SM_CONTROLLER"
VALUE"4.75K"
TOLERANCE"1%"
MATERIAL"EMPTY"
PART_NUMBER"G21796-072"
LOCATION"R25W114"
WATTAGE"1/16W"
PACK_TYPE"0402";
"B"
$PN"2"21;
"A"
$PN"1"2;
%"RES"
"1","(-6875,475)","0","mstr_discrete","I47";
;
CDS_SEC"1"
$SEC"1"
CDS_LOCATION"R25W115"
CDS_LIB"mstr_discrete"
BOM_COST"SM_CONTROLLER"
ROOM"BMC"
PACK_TYPE"0402"
VALUE"4.75K"
PART_NUMBER"G21796-072"
WATTAGE"1/16W"
MATERIAL"CHIP"
TOLERANCE"1%"
LOCATION"R25W115";
"B"
$PN"2"12;
"A"
$PN"1"2;
%"RES"
"2","(-6825,225)","1","mstr_discrete","I48";
;
CDS_LOCATION"R25W116"
CDS_SEC"1"
CDS_LIB"mstr_discrete"
ROOM"NIC_SPRV"
SEC_TYPE"0402"
BOM_COST"NT_GBE_BASE"
SEC"1"
LOCATION"R25W116"
TOLERANCE"1%"
VALUE"3.32K"
WATTAGE"1/16W"
MATERIAL"CHIP"
PACK_TYPE"0402"
PART_NUMBER"G21796-027";
"A"
$PN"1"1;
"B"
$PN"2"18;
%"RES"
"1","(-6900,4675)","0","mstr_discrete","I9";
;
CDS_LOCATION"R25W94"
SEC_TYPE"0402"
SEC"1"
BOM_COST"SM_CONTROLLER"
ROOM"BMC"
CDS_LIB"mstr_discrete"
CDS_SEC"1"
WATTAGE"1/16W"
TOLERANCE"1%"
VALUE"4.75K"
PACK_TYPE"0402"
LOCATION"R25W94"
PART_NUMBER"G21796-072"
MATERIAL"CHIP";
"B"
$PN"2"23;
"A"
$PN"1"2;
END.
